# T6G (Grand Teton) — schematic netlist excerpt (pin names and nets, part order shuffled) for the footprints in the layout excerpt that follows; sources: Cadence DE-HDL packaged netlist, KiCad conversion of 04192023_DAF0TMB3IC0_F0TG_MB_C_brd_V02_OCP.brd

R4192  Q_RES  1K 1% EMPTY  pkg 0402LF  page 235 : A = P3V3_AUX ; B = U273_3_ADD1
PR6818  Q_RES  1K 1% EMPTY  pkg 0402LF  page 364 : A = P3V3_AUX ; B = TP_P0V9_RETIMER_CPU1_SVID_ALERT_N

(kicad_pcb
	(version 20260206)
	(generator "pcbnew")
	(generator_version "10.0")
	(general
		(thickness 1.6)
		(legacy_teardrops no)
	)
	(paper "A4")
	(title_block
		(title "04192023_DAF0TMB3IC0_F0TG_MB_C_brd_V02_OCP.brd")
		(comment 1 "Grand Teton / footprints 4304-4305 of 8354")
	)
	(layers
		(0 "F.Cu" signal "TOP")
		(4 "In1.Cu" signal "GND")
		(6 "In2.Cu" signal "IN1")
		(8 "In3.Cu" signal "GND1")
		(10 "In4.Cu" signal "IN2")
		(12 "In5.Cu" signal "GND2")
		(14 "In6.Cu" signal "IN3")
		(16 "In7.Cu" signal "GND3")
		(18 "In8.Cu" signal "VCC")
		(20 "In9.Cu" signal "VCC1")
		(22 "In10.Cu" signal "GND4")
		(24 "In11.Cu" signal "IN4")
		(26 "In12.Cu" signal "GND5")
		(28 "In13.Cu" signal "IN5")
		(30 "In14.Cu" signal "GND6")
		(32 "In15.Cu" signal "IN6")
		(34 "In16.Cu" signal "GND7")
		(2 "B.Cu" signal "BOTTOM")
		(9 "F.Adhes" user "F.Adhesive")
		(11 "B.Adhes" user "B.Adhesive")
		(13 "F.Paste" user "Package Geometry/Pastemask Top")
		(15 "B.Paste" user "Package Geometry/Pastemask Bottom")
		(5 "F.SilkS" user "Ref Des/Silkscreen Top")
		(7 "B.SilkS" user "Ref Des/Silkscreen Bottom")
		(1 "F.Mask" user "Board Geometry/Soldermask Top")
		(3 "B.Mask" user "Board Geometry/Soldermask Bottom")
		(17 "Dwgs.User" user "User.Drawings")
		(19 "Cmts.User" user "User.Comments")
		(21 "Eco1.User" user "User.Eco1")
		(23 "Eco2.User" user "User.Eco2")
		(25 "Edge.Cuts" user "Board Geometry/Outline")
		(27 "Margin" user)
		(31 "F.CrtYd" user "Package Geometry/Place Bound Top")
		(29 "B.CrtYd" user "Package Geometry/Place Bound Bottom")
		(35 "F.Fab" user "Ref Des/Assembly Top")
		(33 "B.Fab" user "Ref Des/Assembly Bottom")
	)
	(footprint ""
		(layer "F.Cu")
		(at 20.480782 -412.850584 180)
		(property "Reference" "PR6818"
			(at 0 0 180)
			(layer "F.SilkS")
			(hide yes)
			(effects
				(font
					(size 1.27 1.27)
				)
			)
		)
		(property "Value" ""
			(at 0 0 180)
			(layer "F.Fab")
			(effects
				(font
					(size 1.27 1.27)
				)
			)
		)
		(duplicate_pad_numbers_are_jumpers no)
		(fp_line
			(start 0.7874 0.4064)
			(end -0.7874 0.4064)
			(stroke
				(width 0.1524)
				(type default)
			)
			(layer "F.SilkS")
		)
		(fp_line
			(start 0.7874 -0.4064)
			(end 0.7874 0.4064)
			(stroke
				(width 0.1524)
				(type default)
			)
			(layer "F.SilkS")
		)
		(fp_line
			(start -0.7874 0.4064)
			(end -0.7874 -0.4064)
			(stroke
				(width 0.1524)
				(type default)
			)
			(layer "F.SilkS")
		)
		(fp_line
			(start -0.7874 -0.4064)
			(end 0.7874 -0.4064)
			(stroke
				(width 0.1524)
				(type default)
			)
			(layer "F.SilkS")
		)
		(fp_line
			(start 0.67945 0.3048)
			(end 0.120396 0.3048)
			(stroke
				(width 0.1)
				(type default)
			)
			(layer "F.Fab")
		)
		(fp_line
			(start 0.67945 -0.3048)
			(end 0.67945 0.3048)
			(stroke
				(width 0.1)
				(type default)
			)
			(layer "F.Fab")
		)
		(fp_line
			(start 0.12065 -0.2794)
			(end 0.12065 -0.3048)
			(stroke
				(width 0.1)
				(type default)
			)
			(layer "F.Fab")
		)
		(fp_line
			(start 0.12065 -0.3048)
			(end 0.67945 -0.3048)
			(stroke
				(width 0.1)
				(type default)
			)
			(layer "F.Fab")
		)
		(fp_line
			(start 0.120396 0.3048)
			(end 0.120396 0.2794)
			(stroke
				(width 0.1)
				(type default)
			)
			(layer "F.Fab")
		)
		(fp_line
			(start 0.120396 0.2794)
			(end -0.12065 0.2794)
			(stroke
				(width 0.1)
				(type default)
			)
			(layer "F.Fab")
		)
		(fp_line
			(start -0.12065 0.3048)
			(end -0.67945 0.3048)
			(stroke
				(width 0.1)
				(type default)
			)
			(layer "F.Fab")
		)
		(fp_line
			(start -0.12065 0.2794)
			(end -0.12065 0.3048)
			(stroke
				(width 0.1)
				(type default)
			)
			(layer "F.Fab")
		)
		(fp_line
			(start -0.12065 -0.2794)
			(end 0.12065 -0.2794)
			(stroke
				(width 0.1)
				(type default)
			)
			(layer "F.Fab")
		)
		(fp_line
			(start -0.12065 -0.305054)
			(end -0.12065 -0.2794)
			(stroke
				(width 0.1)
				(type default)
			)
			(layer "F.Fab")
		)
		(fp_line
			(start -0.67945 0.3048)
			(end -0.67945 -0.305054)
			(stroke
				(width 0.1)
				(type default)
			)
			(layer "F.Fab")
		)
		(fp_line
			(start -0.67945 -0.305054)
			(end -0.12065 -0.305054)
			(stroke
				(width 0.1)
				(type default)
			)
			(layer "F.Fab")
		)
		(pad "1" smd circle
			(at -0.40005 0 180)
			(size 0 0)
			(layers "F.Cu" "F.Mask" "F.Paste")
			(net "P3V3_AUX")
		)
		(pad "2" smd circle
			(at 0.40005 0 180)
			(size 0 0)
			(layers "F.Cu" "F.Mask" "F.Paste")
			(net "TP_P0V9_RETIMER_CPU1_SVID_ALERT_N")
		)
	)
	(footprint ""
		(layer "F.Cu")
		(at 123.795282 -15.26667 180)
		(property "Reference" "R4192"
			(at 0 0 180)
			(layer "F.SilkS")
			(hide yes)
			(effects
				(font
					(size 1.27 1.27)
				)
			)
		)
		(property "Value" ""
			(at 0 0 180)
			(layer "F.Fab")
			(effects
				(font
					(size 1.27 1.27)
				)
			)
		)
		(duplicate_pad_numbers_are_jumpers no)
		(fp_line
			(start 0.7874 0.4064)
			(end -0.7874 0.4064)
			(stroke
				(width 0.1524)
				(type default)
			)
			(layer "F.SilkS")
		)
		(fp_line
			(start 0.7874 -0.4064)
			(end 0.7874 0.4064)
			(stroke
				(width 0.1524)
				(type default)
			)
			(layer "F.SilkS")
		)
		(fp_line
			(start -0.7874 0.4064)
			(end -0.7874 -0.4064)
			(stroke
				(width 0.1524)
				(type default)
			)
			(layer "F.SilkS")
		)
		(fp_line
			(start -0.7874 -0.4064)
			(end 0.7874 -0.4064)
			(stroke
				(width 0.1524)
				(type default)
			)
			(layer "F.SilkS")
		)
		(fp_line
			(start 0.67945 0.3048)
			(end 0.120396 0.3048)
			(stroke
				(width 0.1)
				(type default)
			)
			(layer "F.Fab")
		)
		(fp_line
			(start 0.67945 -0.3048)
			(end 0.67945 0.3048)
			(stroke
				(width 0.1)
				(type default)
			)
			(layer "F.Fab")
		)
		(fp_line
			(start 0.12065 -0.2794)
			(end 0.12065 -0.3048)
			(stroke
				(width 0.1)
				(type default)
			)
			(layer "F.Fab")
		)
		(fp_line
			(start 0.12065 -0.3048)
			(end 0.67945 -0.3048)
			(stroke
				(width 0.1)
				(type default)
			)
			(layer "F.Fab")
		)
		(fp_line
			(start 0.120396 0.3048)
			(end 0.120396 0.2794)
			(stroke
				(width 0.1)
				(type default)
			)
			(layer "F.Fab")
		)
		(fp_line
			(start 0.120396 0.2794)
			(end -0.12065 0.2794)
			(stroke
				(width 0.1)
				(type default)
			)
			(layer "F.Fab")
		)
		(fp_line
			(start -0.12065 0.3048)
			(end -0.67945 0.3048)
			(stroke
				(width 0.1)
				(type default)
			)
			(layer "F.Fab")
		)
		(fp_line
			(start -0.12065 0.2794)
			(end -0.12065 0.3048)
			(stroke
				(width 0.1)
				(type default)
			)
			(layer "F.Fab")
		)
		(fp_line
			(start -0.12065 -0.2794)
			(end 0.12065 -0.2794)
			(stroke
				(width 0.1)
				(type default)
			)
			(layer "F.Fab")
		)
		(fp_line
			(start -0.12065 -0.305054)
			(end -0.12065 -0.2794)
			(stroke
				(width 0.1)
				(type default)
			)
			(layer "F.Fab")
		)
		(fp_line
			(start -0.67945 0.3048)
			(end -0.67945 -0.305054)
			(stroke
				(width 0.1)
				(type default)
			)
			(layer "F.Fab")
		)
		(fp_line
			(start -0.67945 -0.305054)
			(end -0.12065 -0.305054)
			(stroke
				(width 0.1)
				(type default)
			)
			(layer "F.Fab")
		)
		(pad "1" smd circle
			(at -0.40005 0 180)
			(size 0 0)
			(layers "F.Cu" "F.Mask" "F.Paste")
			(net "P3V3_AUX")
		)
		(pad "2" smd circle
			(at 0.40005 0 180)
			(size 0 0)
			(layers "F.Cu" "F.Mask" "F.Paste")
			(net "U273_3_ADD1")
		)
	)
)
